FILE_TYPE = CONNECTIVITY;
{Allegro Design Entry HDL 16.6-p007 (v16-6-112F) 10/10/2012}
"PAGE_NUMBER" = 70;
0"NC";
1"PVCCMCP_CPU1\g";
2"PVCCMCP_CPU1\g";
3"PVCCMCP_CPU1\g";
4"PVCCIOMCP_CPU1\g";
5"TP_CPU1_RSVD_168";
6"TP_CPU1_RSVD_149";
7"TP_CPU1_RSVD_148";
8"TP_CPU1_RSVD_144";
9"TP_CPU1_RSVD_145";
10"TP_CPU1_RSVD_146";
11"TP_CPU1_RSVD_147";
12"TP_CPU1_RSVD_150";
13"CLK_100M_CPU1_RC_REFCLK1_DP";
14"TP_CPU1_RSVD_152";
15"TP_CPU1_RSVD_151";
16"TP_CPU1_RSVD_154";
17"TP_CPU1_RSVD_255";
18"TP_CPU1_RSVD_171";
19"TP_CPU1_RSVD_170";
20"TP_CPU1_RSVD_169";
21"TP_CPU1_RSVD_167";
22"TP_CPU1_RSVD_166";
23"CLK_100M_CPU1_RC_REFCLK1_DN";
24"TP_CPU1_RSVD_164";
25"TP_CPU1_RSVD_163";
26"TP_CPU1_RSVD_162";
27"TP_CPU1_RSVD_161";
28"TP_CPU1_RSVD_160";
29"TP_CPU1_RSVD_159";
30"TP_CPU1_RSVD_158";
31"TP_CPU1_RSVD_157";
32"TP_CPU1_RSVD_156";
33"TP_CPU1_RSVD_155";
34"TP_CPU1_RSVD_124";
35"TP_CPU1_RSVD_123";
36"TP_CPU1_RSVD_121";
37"TP_CPU1_RSVD_119";
38"TP_CPU1_RSVD_117";
39"TP_CPU1_RSVD_114";
40"TP_CPU1_RSVD_113";
41"TP_CPU1_RSVD_111";
42"TP_CPU1_RSVD_108";
43"TP_CPU1_RSVD_106";
44"TP_CPU1_RSVD_105";
45"TP_CPU1_RSVD_101";
46"TP_CPU1_RSVD_100";
47"TP_CPU1_RSVD_99";
48"TP_CPU1_RSVD_97";
49"TP_CPU1_RSVD_95";
50"TP_CPU1_RSVD_94";
51"TP_CPU1_TEST_9";
52"TP_CPU1_TEST_8";
53"TP_CPU1_TEST_7";
54"TP_CPU1_TEST_6";
55"TP_CPU1_TEST_10";
56"TP_CPU1_RSVD_82";
57"TP_CPU1_RSVD_85";
58"TP_CPU1_RSVD_90";
59"TP_CPU1_RSVD_91";
%"SKX_EXT_B"
"17","(-2925,2575)","0","chpset_lib","I10";
;
CDS_SEC"17"
MATERIAL"IC"
LOCATION"U2D1"
PART_NUMBER"TBD"
CDS_LOCATION"U2D1"
SEC"17"
CDS_LIB"chpset_lib"
SEC_TYPE"BGA1"
PACK_TYPE"BGA1";
"TEST_9"
$PN"AW20"51;
"TEST_8"
$PN"AW16"52;
"TEST_7"
$PN"AU18"53;
"TEST_6"
$PN"AR16"54;
"TEST_10"
$PN"AW22"55;
"RSVD<81>"
$PN"CL24"1;
"RSVD<82>"
$PN"CK77"56;
"RSVD<83>"
$PN"CK25"1;
"RSVD<84>"
$PN"CK23"1;
"RSVD<85>"
$PN"CK19"57;
"RSVD<86>"
$PN"CJ26"1;
"RSVD<87>"
$PN"CJ24"1;
"RSVD<88>"
$PN"CJ22"1;
"RSVD<89>"
$PN"CJ20"1;
"RSVD<90>"
$PN"CH77"58;
"RSVD<91>"
$PN"CH25"59;
%"VCC_CORE"
"1","(-1225,2825)","0","mstr_symbols","I12";
;
HDL_POWER"PVCCMCP_CPU1"
CDS_LIB"mstr_symbols";
"A"1;
%"VCC_CORE"
"1","(-4000,3775)","0","mstr_symbols","I13";
;
HDL_POWER"PVCCMCP_CPU1"
CDS_LIB"mstr_symbols";
"A"2;
%"VCC_CORE"
"1","(-7500,2350)","0","mstr_symbols","I15";
;
HDL_POWER"PVCCMCP_CPU1"
CDS_LIB"mstr_symbols";
"A"3;
%"VCC_CORE"
"1","(-7500,2100)","0","mstr_symbols","I16";
;
HDL_POWER"PVCCIOMCP_CPU1"
VOLTAGE"+0.95V"
CDS_LIB"mstr_symbols";
"A"4;
%"SKX_EXT_B"
"16","(-5450,2550)","0","chpset_lib","I9";
;
CDS_SEC"16"
LOCATION"U2D1"
PART_NUMBER"TBD"
MATERIAL"IC"
PACK_TYPE"BGA1"
SEC_TYPE"BGA1"
CDS_LIB"chpset_lib"
SEC"16"
CDS_LOCATION"U2D1";
"RSVD<92>"
$PN"CH23"2;
"RSVD<93>"
$PN"CH21"2;
"RSVD<94>"
$PN"CG82"50;
"RSVD<95>"
$PN"CG78"49;
"RSVD<96>"
$PN"CG26"2;
"RSVD<97>"
$PN"CG24"48;
"RSVD<98>"
$PN"CG20"2;
"RSVD<99>"
$PN"CG10"47;
"RSVD<100>"
$PN"CF81"46;
"RSVD<101>"
$PN"CF79"45;
"RSVD<102>"
$PN"CF23"2;
"RSVD<103>"
$PN"CF21"2;
"RSVD<104>"
$PN"CF19"2;
"RSVD<105>"
$PN"CE80"44;
"RSVD<106>"
$PN"CE78"43;
"RSVD<107>"
$PN"CE22"2;
"RSVD<108>"
$PN"CD25"42;
"RSVD<109>"
$PN"CD21"2;
"RSVD<110>"
$PN"CD19"2;
"RSVD<111>"
$PN"CC6"41;
"RSVD<112>"
$PN"CC20"2;
"RSVD<113>"
$PN"CB5"40;
"RSVD<114>"
$PN"CB25"39;
"RSVD<115>"
$PN"CB21"2;
"RSVD<116>"
$PN"CB19"2;
"RSVD<117>"
$PN"CA24"38;
"RSVD<118>"
$PN"CA22"2;
"RSVD<119>"
$PN"BY25"37;
"RSVD<120>"
$PN"BY19"2;
"RSVD<121>"
$PN"BW22"36;
"RSVD<122>"
$PN"BW20"2;
"RSVD<123>"
$PN"BW10"35;
"RSVD<124>"
$PN"BV23"34;
"RSVD<125>"
$PN"BV21"2;
"RSVD<126>"
$PN"BV19"2;
"RSVD<127>"
$PN"BU22"3;
"RSVD<128>"
$PN"BU20"3;
"RSVD<129>"
$PN"BU18"4;
"RSVD<130>"
$PN"BR24"3;
"RSVD<131>"
$PN"BR22"3;
"RSVD<132>"
$PN"BP21"3;
"RSVD<133>"
$PN"BP17"4;
"RSVD<134>"
$PN"BN18"4;
"RSVD<135>"
$PN"BM19"3;
"RSVD<136>"
$PN"BM17"4;
"RSVD<137>"
$PN"BL20"3;
"RSVD<138>"
$PN"BL18"4;
"RSVD<139>"
$PN"BK17"3;
"RSVD<140>"
$PN"BJ20"3;
"RSVD<141>"
$PN"BJ18"3;
"RSVD<142>"
$PN"BJ16"3;
"RSVD<143>"
$PN"BH19"3;
"RSVD<144>"
$PN"BG20"8;
"RSVD<145>"
$PN"BG18"9;
"RSVD<146>"
$PN"BF21"10;
"RSVD<147>"
$PN"BE22"11;
"RSVD<148>"
$PN"BE20"7;
"RSVD<149>"
$PN"BE18"6;
"RSVD<150>"
$PN"BD69"12;
"RSVD<151>"
$PN"BD67"15;
"RSVD<152>"
$PN"BD65"14;
"RSVD<153>"
$PN"BD25"13;
"RSVD<154>"
$PN"BD19"16;
"RSVD<155>"
$PN"BD17"33;
"RSVD<156>"
$PN"BC68"32;
"RSVD<157>"
$PN"BC66"31;
"RSVD<158>"
$PN"BC64"30;
"RSVD<159>"
$PN"BC22"29;
"RSVD<160>"
$PN"BC20"28;
"RSVD<161>"
$PN"BC18"27;
"RSVD<162>"
$PN"BC14"26;
"RSVD<163>"
$PN"BB67"25;
"RSVD<164>"
$PN"BB65"24;
"RSVD<165>"
$PN"BB25"23;
"RSVD<166>"
$PN"BB21"22;
"RSVD<167>"
$PN"BB17"21;
"RSVD<168>"
$PN"BB15"5;
"RSVD<169>"
$PN"BB13"20;
"RSVD<170>"
$PN"BA82"19;
"RSVD<171>"
$PN"BA78"18;
"RSVD<255>"
$PN"AY83"17;
END.
